# T6G (Grand Teton) — schematic netlist excerpt (pin names and nets, part order shuffled) for the footprints in the layout excerpt that follows; sources: Cadence DE-HDL packaged netlist, KiCad conversion of 04192023_DAF0TMB3IC0_F0TG_MB_C_brd_V02_OCP.brd

R3459  Q_RES  1K 1% CHIP  pkg 0402LF  page 129 : A = P3V3_AUX ; B = GPU_NVS_PWR_BRAKE_N
R2937  Q_RES  4.7K 5% CHIP  pkg 0402LF  page 130 : A = FM_GPU_PWR_EN_R ; B = GND

(kicad_pcb
	(version 20260206)
	(generator "pcbnew")
	(generator_version "10.0")
	(general
		(thickness 1.6)
		(legacy_teardrops no)
	)
	(paper "A4")
	(title_block
		(title "04192023_DAF0TMB3IC0_F0TG_MB_C_brd_V02_OCP.brd")
		(comment 1 "Grand Teton / footprints 1563-1564 of 8354")
	)
	(layers
		(0 "F.Cu" signal "TOP")
		(4 "In1.Cu" signal "GND")
		(6 "In2.Cu" signal "IN1")
		(8 "In3.Cu" signal "GND1")
		(10 "In4.Cu" signal "IN2")
		(12 "In5.Cu" signal "GND2")
		(14 "In6.Cu" signal "IN3")
		(16 "In7.Cu" signal "GND3")
		(18 "In8.Cu" signal "VCC")
		(20 "In9.Cu" signal "VCC1")
		(22 "In10.Cu" signal "GND4")
		(24 "In11.Cu" signal "IN4")
		(26 "In12.Cu" signal "GND5")
		(28 "In13.Cu" signal "IN5")
		(30 "In14.Cu" signal "GND6")
		(32 "In15.Cu" signal "IN6")
		(34 "In16.Cu" signal "GND7")
		(2 "B.Cu" signal "BOTTOM")
		(9 "F.Adhes" user "F.Adhesive")
		(11 "B.Adhes" user "B.Adhesive")
		(13 "F.Paste" user "Package Geometry/Pastemask Top")
		(15 "B.Paste" user "Package Geometry/Pastemask Bottom")
		(5 "F.SilkS" user "Ref Des/Silkscreen Top")
		(7 "B.SilkS" user "Ref Des/Silkscreen Bottom")
		(1 "F.Mask" user "Board Geometry/Soldermask Top")
		(3 "B.Mask" user "Board Geometry/Soldermask Bottom")
		(17 "Dwgs.User" user "User.Drawings")
		(19 "Cmts.User" user "User.Comments")
		(21 "Eco1.User" user "User.Eco1")
		(23 "Eco2.User" user "User.Eco2")
		(25 "Edge.Cuts" user "Board Geometry/Outline")
		(27 "Margin" user)
		(31 "F.CrtYd" user "Package Geometry/Place Bound Top")
		(29 "B.CrtYd" user "Package Geometry/Place Bound Bottom")
		(35 "F.Fab" user "Ref Des/Assembly Top")
		(33 "B.Fab" user "Ref Des/Assembly Bottom")
	)
	(footprint ""
		(layer "F.Cu")
		(at 44.069 -438.15 180)
		(property "Reference" "R2937"
			(at 0 0 180)
			(layer "F.SilkS")
			(hide yes)
			(effects
				(font
					(size 1.27 1.27)
				)
			)
		)
		(property "Value" ""
			(at 0 0 180)
			(layer "F.Fab")
			(effects
				(font
					(size 1.27 1.27)
				)
			)
		)
		(duplicate_pad_numbers_are_jumpers no)
		(fp_line
			(start 0.7874 0.4064)
			(end -0.7874 0.4064)
			(stroke
				(width 0.1524)
				(type default)
			)
			(layer "F.SilkS")
		)
		(fp_line
			(start 0.7874 -0.4064)
			(end 0.7874 0.4064)
			(stroke
				(width 0.1524)
				(type default)
			)
			(layer "F.SilkS")
		)
		(fp_line
			(start -0.7874 0.4064)
			(end -0.7874 -0.4064)
			(stroke
				(width 0.1524)
				(type default)
			)
			(layer "F.SilkS")
		)
		(fp_line
			(start -0.7874 -0.4064)
			(end 0.7874 -0.4064)
			(stroke
				(width 0.1524)
				(type default)
			)
			(layer "F.SilkS")
		)
		(fp_line
			(start 0.67945 0.3048)
			(end 0.120396 0.3048)
			(stroke
				(width 0.1)
				(type default)
			)
			(layer "F.Fab")
		)
		(fp_line
			(start 0.67945 -0.3048)
			(end 0.67945 0.3048)
			(stroke
				(width 0.1)
				(type default)
			)
			(layer "F.Fab")
		)
		(fp_line
			(start 0.12065 -0.2794)
			(end 0.12065 -0.3048)
			(stroke
				(width 0.1)
				(type default)
			)
			(layer "F.Fab")
		)
		(fp_line
			(start 0.12065 -0.3048)
			(end 0.67945 -0.3048)
			(stroke
				(width 0.1)
				(type default)
			)
			(layer "F.Fab")
		)
		(fp_line
			(start 0.120396 0.3048)
			(end 0.120396 0.2794)
			(stroke
				(width 0.1)
				(type default)
			)
			(layer "F.Fab")
		)
		(fp_line
			(start 0.120396 0.2794)
			(end -0.12065 0.2794)
			(stroke
				(width 0.1)
				(type default)
			)
			(layer "F.Fab")
		)
		(fp_line
			(start -0.12065 0.3048)
			(end -0.67945 0.3048)
			(stroke
				(width 0.1)
				(type default)
			)
			(layer "F.Fab")
		)
		(fp_line
			(start -0.12065 0.2794)
			(end -0.12065 0.3048)
			(stroke
				(width 0.1)
				(type default)
			)
			(layer "F.Fab")
		)
		(fp_line
			(start -0.12065 -0.2794)
			(end 0.12065 -0.2794)
			(stroke
				(width 0.1)
				(type default)
			)
			(layer "F.Fab")
		)
		(fp_line
			(start -0.12065 -0.305054)
			(end -0.12065 -0.2794)
			(stroke
				(width 0.1)
				(type default)
			)
			(layer "F.Fab")
		)
		(fp_line
			(start -0.67945 0.3048)
			(end -0.67945 -0.305054)
			(stroke
				(width 0.1)
				(type default)
			)
			(layer "F.Fab")
		)
		(fp_line
			(start -0.67945 -0.305054)
			(end -0.12065 -0.305054)
			(stroke
				(width 0.1)
				(type default)
			)
			(layer "F.Fab")
		)
		(pad "1" smd circle
			(at -0.40005 0 180)
			(size 0 0)
			(layers "F.Cu" "F.Mask" "F.Paste")
			(net "FM_GPU_PWR_EN_R")
		)
		(pad "2" smd circle
			(at 0.40005 0 180)
			(size 0 0)
			(layers "F.Cu" "F.Mask" "F.Paste")
			(net "GND")
		)
	)
	(footprint ""
		(layer "F.Cu")
		(at 104.902 -426.466 -90)
		(property "Reference" "R3459"
			(at 0 0 270)
			(layer "F.SilkS")
			(hide yes)
			(effects
				(font
					(size 1.27 1.27)
				)
			)
		)
		(property "Value" ""
			(at 0 0 270)
			(layer "F.Fab")
			(effects
				(font
					(size 1.27 1.27)
				)
			)
		)
		(duplicate_pad_numbers_are_jumpers no)
		(fp_line
			(start -0.7874 0.4064)
			(end -0.7874 -0.4064)
			(stroke
				(width 0.1524)
				(type default)
			)
			(layer "F.SilkS")
		)
		(fp_line
			(start 0.7874 0.4064)
			(end -0.7874 0.4064)
			(stroke
				(width 0.1524)
				(type default)
			)
			(layer "F.SilkS")
		)
		(fp_line
			(start -0.7874 -0.4064)
			(end 0.7874 -0.4064)
			(stroke
				(width 0.1524)
				(type default)
			)
			(layer "F.SilkS")
		)
		(fp_line
			(start 0.7874 -0.4064)
			(end 0.7874 0.4064)
			(stroke
				(width 0.1524)
				(type default)
			)
			(layer "F.SilkS")
		)
		(fp_line
			(start -0.67945 0.3048)
			(end -0.67945 -0.305054)
			(stroke
				(width 0.1)
				(type default)
			)
			(layer "F.Fab")
		)
		(fp_line
			(start -0.12065 0.3048)
			(end -0.67945 0.3048)
			(stroke
				(width 0.1)
				(type default)
			)
			(layer "F.Fab")
		)
		(fp_line
			(start 0.120396 0.3048)
			(end 0.120396 0.2794)
			(stroke
				(width 0.1)
				(type default)
			)
			(layer "F.Fab")
		)
		(fp_line
			(start 0.67945 0.3048)
			(end 0.120396 0.3048)
			(stroke
				(width 0.1)
				(type default)
			)
			(layer "F.Fab")
		)
		(fp_line
			(start -0.12065 0.2794)
			(end -0.12065 0.3048)
			(stroke
				(width 0.1)
				(type default)
			)
			(layer "F.Fab")
		)
		(fp_line
			(start 0.120396 0.2794)
			(end -0.12065 0.2794)
			(stroke
				(width 0.1)
				(type default)
			)
			(layer "F.Fab")
		)
		(fp_line
			(start -0.12065 -0.2794)
			(end 0.12065 -0.2794)
			(stroke
				(width 0.1)
				(type default)
			)
			(layer "F.Fab")
		)
		(fp_line
			(start 0.12065 -0.2794)
			(end 0.12065 -0.3048)
			(stroke
				(width 0.1)
				(type default)
			)
			(layer "F.Fab")
		)
		(fp_line
			(start 0.12065 -0.3048)
			(end 0.67945 -0.3048)
			(stroke
				(width 0.1)
				(type default)
			)
			(layer "F.Fab")
		)
		(fp_line
			(start 0.67945 -0.3048)
			(end 0.67945 0.3048)
			(stroke
				(width 0.1)
				(type default)
			)
			(layer "F.Fab")
		)
		(fp_line
			(start -0.67945 -0.305054)
			(end -0.12065 -0.305054)
			(stroke
				(width 0.1)
				(type default)
			)
			(layer "F.Fab")
		)
		(fp_line
			(start -0.12065 -0.305054)
			(end -0.12065 -0.2794)
			(stroke
				(width 0.1)
				(type default)
			)
			(layer "F.Fab")
		)
		(pad "1" smd circle
			(at -0.40005 0 270)
			(size 0 0)
			(layers "F.Cu" "F.Mask" "F.Paste")
			(net "P3V3_AUX")
		)
		(pad "2" smd circle
			(at 0.40005 0 270)
			(size 0 0)
			(layers "F.Cu" "F.Mask" "F.Paste")
			(net "GPU_NVS_PWR_BRAKE_N")
		)
	)
)
